# T6G (Grand Teton) — schematic netlist excerpt (pin names and nets, part order shuffled) for the footprints in the layout excerpt that follows; sources: Cadence DE-HDL packaged netlist, KiCad conversion of 04192023_DAF0TMB3IC0_F0TG_MB_C_brd_V02_OCP.brd

C33  Q_CAP  0.1UF 25V 10% X7R  pkg 0402  page 257 : A = P12V_OCP_V3_2_ISENSE_TIC ; B = GND
R4492  Q_RES  10K 1% CHIP  pkg 0402LF  page 182 : A = CLK_9ZXL045_P0_HIBW ; B = GND

(kicad_pcb
	(version 20260206)
	(generator "pcbnew")
	(generator_version "10.0")
	(general
		(thickness 1.6)
		(legacy_teardrops no)
	)
	(paper "A4")
	(title_block
		(title "04192023_DAF0TMB3IC0_F0TG_MB_C_brd_V02_OCP.brd")
		(comment 1 "Grand Teton / footprints 1771-1772 of 8354")
	)
	(layers
		(0 "F.Cu" signal "TOP")
		(4 "In1.Cu" signal "GND")
		(6 "In2.Cu" signal "IN1")
		(8 "In3.Cu" signal "GND1")
		(10 "In4.Cu" signal "IN2")
		(12 "In5.Cu" signal "GND2")
		(14 "In6.Cu" signal "IN3")
		(16 "In7.Cu" signal "GND3")
		(18 "In8.Cu" signal "VCC")
		(20 "In9.Cu" signal "VCC1")
		(22 "In10.Cu" signal "GND4")
		(24 "In11.Cu" signal "IN4")
		(26 "In12.Cu" signal "GND5")
		(28 "In13.Cu" signal "IN5")
		(30 "In14.Cu" signal "GND6")
		(32 "In15.Cu" signal "IN6")
		(34 "In16.Cu" signal "GND7")
		(2 "B.Cu" signal "BOTTOM")
		(9 "F.Adhes" user "F.Adhesive")
		(11 "B.Adhes" user "B.Adhesive")
		(13 "F.Paste" user "Package Geometry/Pastemask Top")
		(15 "B.Paste" user "Package Geometry/Pastemask Bottom")
		(5 "F.SilkS" user "Ref Des/Silkscreen Top")
		(7 "B.SilkS" user "Ref Des/Silkscreen Bottom")
		(1 "F.Mask" user "Board Geometry/Soldermask Top")
		(3 "B.Mask" user "Board Geometry/Soldermask Bottom")
		(17 "Dwgs.User" user "User.Drawings")
		(19 "Cmts.User" user "User.Comments")
		(21 "Eco1.User" user "User.Eco1")
		(23 "Eco2.User" user "User.Eco2")
		(25 "Edge.Cuts" user "Board Geometry/Outline")
		(27 "Margin" user)
		(31 "F.CrtYd" user "Package Geometry/Place Bound Top")
		(29 "B.CrtYd" user "Package Geometry/Place Bound Bottom")
		(35 "F.Fab" user "Ref Des/Assembly Top")
		(33 "B.Fab" user "Ref Des/Assembly Bottom")
	)
	(footprint ""
		(layer "F.Cu")
		(at 283.464 -423.418 90)
		(property "Reference" "R4492"
			(at 0 0 90)
			(layer "F.SilkS")
			(hide yes)
			(effects
				(font
					(size 1.27 1.27)
				)
			)
		)
		(property "Value" ""
			(at 0 0 90)
			(layer "F.Fab")
			(effects
				(font
					(size 1.27 1.27)
				)
			)
		)
		(duplicate_pad_numbers_are_jumpers no)
		(fp_line
			(start 0.7874 -0.4064)
			(end 0.7874 0.4064)
			(stroke
				(width 0.1524)
				(type default)
			)
			(layer "F.SilkS")
		)
		(fp_line
			(start -0.7874 -0.4064)
			(end 0.7874 -0.4064)
			(stroke
				(width 0.1524)
				(type default)
			)
			(layer "F.SilkS")
		)
		(fp_line
			(start 0.7874 0.4064)
			(end -0.7874 0.4064)
			(stroke
				(width 0.1524)
				(type default)
			)
			(layer "F.SilkS")
		)
		(fp_line
			(start -0.7874 0.4064)
			(end -0.7874 -0.4064)
			(stroke
				(width 0.1524)
				(type default)
			)
			(layer "F.SilkS")
		)
		(fp_line
			(start -0.12065 -0.305054)
			(end -0.12065 -0.2794)
			(stroke
				(width 0.1)
				(type default)
			)
			(layer "F.Fab")
		)
		(fp_line
			(start -0.67945 -0.305054)
			(end -0.12065 -0.305054)
			(stroke
				(width 0.1)
				(type default)
			)
			(layer "F.Fab")
		)
		(fp_line
			(start 0.67945 -0.3048)
			(end 0.67945 0.3048)
			(stroke
				(width 0.1)
				(type default)
			)
			(layer "F.Fab")
		)
		(fp_line
			(start 0.12065 -0.3048)
			(end 0.67945 -0.3048)
			(stroke
				(width 0.1)
				(type default)
			)
			(layer "F.Fab")
		)
		(fp_line
			(start 0.12065 -0.2794)
			(end 0.12065 -0.3048)
			(stroke
				(width 0.1)
				(type default)
			)
			(layer "F.Fab")
		)
		(fp_line
			(start -0.12065 -0.2794)
			(end 0.12065 -0.2794)
			(stroke
				(width 0.1)
				(type default)
			)
			(layer "F.Fab")
		)
		(fp_line
			(start 0.120396 0.2794)
			(end -0.12065 0.2794)
			(stroke
				(width 0.1)
				(type default)
			)
			(layer "F.Fab")
		)
		(fp_line
			(start -0.12065 0.2794)
			(end -0.12065 0.3048)
			(stroke
				(width 0.1)
				(type default)
			)
			(layer "F.Fab")
		)
		(fp_line
			(start 0.67945 0.3048)
			(end 0.120396 0.3048)
			(stroke
				(width 0.1)
				(type default)
			)
			(layer "F.Fab")
		)
		(fp_line
			(start 0.120396 0.3048)
			(end 0.120396 0.2794)
			(stroke
				(width 0.1)
				(type default)
			)
			(layer "F.Fab")
		)
		(fp_line
			(start -0.12065 0.3048)
			(end -0.67945 0.3048)
			(stroke
				(width 0.1)
				(type default)
			)
			(layer "F.Fab")
		)
		(fp_line
			(start -0.67945 0.3048)
			(end -0.67945 -0.305054)
			(stroke
				(width 0.1)
				(type default)
			)
			(layer "F.Fab")
		)
		(pad "1" smd circle
			(at -0.40005 0 90)
			(size 0 0)
			(layers "F.Cu" "F.Mask" "F.Paste")
			(net "CLK_9ZXL045_P0_HIBW")
		)
		(pad "2" smd circle
			(at 0.40005 0 90)
			(size 0 0)
			(layers "F.Cu" "F.Mask" "F.Paste")
			(net "GND")
		)
	)
	(footprint ""
		(layer "F.Cu")
		(at 319.940178 -44.716954)
		(property "Reference" "C33"
			(at 0 0 0)
			(layer "F.SilkS")
			(hide yes)
			(effects
				(font
					(size 1.27 1.27)
				)
			)
		)
		(property "Value" ""
			(at 0 0 0)
			(layer "F.Fab")
			(effects
				(font
					(size 1.27 1.27)
				)
			)
		)
		(duplicate_pad_numbers_are_jumpers no)
		(fp_line
			(start -0.7874 -0.4064)
			(end 0.7874 -0.4064)
			(stroke
				(width 0.1524)
				(type default)
			)
			(layer "F.SilkS")
		)
		(fp_line
			(start -0.7874 0.4064)
			(end -0.7874 -0.4064)
			(stroke
				(width 0.1524)
				(type default)
			)
			(layer "F.SilkS")
		)
		(fp_line
			(start 0.7874 -0.4064)
			(end 0.7874 0.4064)
			(stroke
				(width 0.1524)
				(type default)
			)
			(layer "F.SilkS")
		)
		(fp_line
			(start 0.7874 0.4064)
			(end -0.7874 0.4064)
			(stroke
				(width 0.1524)
				(type default)
			)
			(layer "F.SilkS")
		)
		(fp_line
			(start -0.67945 -0.305054)
			(end -0.12065 -0.305054)
			(stroke
				(width 0.1)
				(type default)
			)
			(layer "F.Fab")
		)
		(fp_line
			(start -0.67945 0.3048)
			(end -0.67945 -0.305054)
			(stroke
				(width 0.1)
				(type default)
			)
			(layer "F.Fab")
		)
		(fp_line
			(start -0.12065 -0.305054)
			(end -0.12065 -0.2794)
			(stroke
				(width 0.1)
				(type default)
			)
			(layer "F.Fab")
		)
		(fp_line
			(start -0.12065 -0.2794)
			(end 0.12065 -0.2794)
			(stroke
				(width 0.1)
				(type default)
			)
			(layer "F.Fab")
		)
		(fp_line
			(start -0.12065 0.2794)
			(end -0.12065 0.3048)
			(stroke
				(width 0.1)
				(type default)
			)
			(layer "F.Fab")
		)
		(fp_line
			(start -0.12065 0.3048)
			(end -0.67945 0.3048)
			(stroke
				(width 0.1)
				(type default)
			)
			(layer "F.Fab")
		)
		(fp_line
			(start 0.120396 0.2794)
			(end -0.12065 0.2794)
			(stroke
				(width 0.1)
				(type default)
			)
			(layer "F.Fab")
		)
		(fp_line
			(start 0.120396 0.3048)
			(end 0.120396 0.2794)
			(stroke
				(width 0.1)
				(type default)
			)
			(layer "F.Fab")
		)
		(fp_line
			(start 0.12065 -0.3048)
			(end 0.67945 -0.3048)
			(stroke
				(width 0.1)
				(type default)
			)
			(layer "F.Fab")
		)
		(fp_line
			(start 0.12065 -0.2794)
			(end 0.12065 -0.3048)
			(stroke
				(width 0.1)
				(type default)
			)
			(layer "F.Fab")
		)
		(fp_line
			(start 0.67945 -0.3048)
			(end 0.67945 0.3048)
			(stroke
				(width 0.1)
				(type default)
			)
			(layer "F.Fab")
		)
		(fp_line
			(start 0.67945 0.3048)
			(end 0.120396 0.3048)
			(stroke
				(width 0.1)
				(type default)
			)
			(layer "F.Fab")
		)
		(pad "1" smd circle
			(at -0.40005 0)
			(size 0 0)
			(layers "F.Cu" "F.Mask" "F.Paste")
			(net "P12V_OCP_V3_2_ISENSE_TIC")
		)
		(pad "2" smd circle
			(at 0.40005 0)
			(size 0 0)
			(layers "F.Cu" "F.Mask" "F.Paste")
			(net "GND")
		)
	)
)
